(kicad_pcb
	(version 20221018)
	(generator pcbnew)
	(general
    (thickness 1.562)
  )
	(paper "A4")
	(title_block
    (title "Thunderbolt PCIe Adaper")
    (date "2024-07-09")
    (rev "1.0.3")
    (comment 1 "www.antmicro.com")
    (comment 2 "Antmicro Ltd.")
		(comment 9 "footprints 177-185 of 271")
	)
	(layers
    (0 "F.Cu" signal)
    (1 "In1.Cu" signal)
    (2 "In2.Cu" signal)
    (3 "In3.Cu" signal)
    (4 "In4.Cu" signal)
    (31 "B.Cu" signal)
    (32 "B.Adhes" user "B.Adhesive")
    (33 "F.Adhes" user "F.Adhesive")
    (34 "B.Paste" user)
    (35 "F.Paste" user)
    (36 "B.SilkS" user "B.Silkscreen")
    (37 "F.SilkS" user "F.Silkscreen")
    (38 "B.Mask" user)
    (39 "F.Mask" user)
    (40 "Dwgs.User" user "User.Drawings")
    (41 "Cmts.User" user "User.Comments")
    (42 "Eco1.User" user "User.Eco1")
    (43 "Eco2.User" user "User.Eco2")
    (44 "Edge.Cuts" user)
    (45 "Margin" user)
    (46 "B.CrtYd" user "B.Courtyard")
    (47 "F.CrtYd" user "F.Courtyard")
    (48 "B.Fab" user)
    (49 "F.Fab" user)
  )
	(footprint "antmicro-footprints:R_0402_1005Metric" (layer "B.Cu")
    (at 157.89 57.39 -90)
    (descr "Resistor SMD 0402")
    (tags "resistor SMD 0402")
    (property "Author" "Antmicro")
    (property "License" "Apache-2.0")
    (property "MPN" "CR0402-FX-1002GLF")
    (property "Manufacturer" "Bourns")
    (property "Sheetfile" "power.kicad_sch")
    (property "Sheetname" "Power")
    (property "Tolerance" "1%")
    (property "Val" "10k")
    (property "ki_description" "SMD Chip Resistor, 10 kohm, ± 1%, 62.5 mW, 0402 [1005 Metric], Thick Film, General Purpose")
    (property "ki_keywords" "0402, SMT, RESISTOR, PASSIVE")
    (attr smd)
    (fp_text reference "R16" (at -3.034 -0.479 90) (layer "B.SilkS")
        (effects (font (size 0.7 0.7) (thickness 0.15)) (justify left bottom mirror))
    )
    (fp_text value "R_10k_0402" (at -1.011843 -1.772047 90) (layer "B.Fab")
        (effects (font (size 0.7 0.7) (thickness 0.15)) (justify left bottom mirror))
    )
    (fp_text user "${REFERENCE}" (at -0.95 -3.168 90) (layer "B.Fab") hide
        (effects (font (size 0.7 0.7) (thickness 0.15)) (justify left bottom mirror))
    )
    (fp_text user "License: Apache-2.0" (at -0.95 -5.169 90) (layer "B.Fab") hide
        (effects (font (size 0.7 0.7) (thickness 0.15)) (justify left bottom mirror))
    )
    (fp_text user "Author: Antmicro" (at -0.95 -4.169 90) (layer "B.Fab") hide
        (effects (font (size 0.7 0.7) (thickness 0.15)) (justify left bottom mirror))
    )
    (fp_rect (start -0.925 0.47) (end 0.925 -0.47)
      (stroke (width 0.05) (type default)) (fill none) (layer "B.CrtYd"))
    (fp_rect (start -0.5 0.25) (end 0.5 -0.25)
      (stroke (width 0.15) (type solid)) (fill none) (layer "B.Fab"))
    (pad "1" smd roundrect (at -0.48 0 270) (size 0.59 0.64) (layers "B.Cu" "B.Paste" "B.Mask") (roundrect_rratio 0.25)
      (net 9 "/Power/TPS_3V3") (pintype "passive"))
    (pad "2" smd roundrect (at 0.48 0 270) (size 0.59 0.64) (layers "B.Cu" "B.Paste" "B.Mask") (roundrect_rratio 0.25)
      (net 151 "Net-(U3-I2C_IRQ2Z)") (pintype "passive"))
  )
	(footprint "antmicro-footprints:C_0402_1005Metric" (layer "B.Cu")
    (at 134.8 76.925)
    (descr "Capacitor SMD 0402")
    (tags "capacitor SMD 0402")
    (property "Author" "Antmicro")
    (property "Dielectric" "")
    (property "License" "Apache-2.0")
    (property "MPN" "C1005X6S1A105K050BC")
    (property "Manufacturer" "TDK")
    (property "Sheetfile" "tb-power.kicad_sch")
    (property "Sheetname" "Thunderbolt Controller - Power")
    (property "Val" "1u")
    (property "Voltage" "")
    (property "ki_description" "SMD Multilayer Ceramic Capacitor, 1 µF, 10 V, 0402 [1005 Metric], ± 10%, X6S, C")
    (property "ki_keywords" "0402, SMT, CAPACITOR, PASSIVE, CERAMIC, MLCC")
    (attr smd)
    (fp_text reference "C61" (at 17.6 7.53 180) (layer "B.SilkS")
        (effects (font (size 0.7 0.7) (thickness 0.15)) (justify left bottom mirror))
    )
    (fp_text value "C_1u_0402" (at -1.022927 -2.155213 180) (layer "B.Fab")
        (effects (font (size 0.7 0.7) (thickness 0.15)) (justify left bottom mirror))
    )
    (fp_text user "${REFERENCE}" (at -0.939 -4.599 180) (layer "B.Fab") hide
        (effects (font (size 0.7 0.7) (thickness 0.15)) (justify left bottom mirror))
    )
    (fp_text user "License: Apache-2.0" (at -0.939 -5.799 180) (layer "B.Fab") hide
        (effects (font (size 0.7 0.7) (thickness 0.15)) (justify left bottom mirror))
    )
    (fp_text user "Author: Antmicro" (at -0.939 -3.399 180) (layer "B.Fab") hide
        (effects (font (size 0.7 0.7) (thickness 0.15)) (justify left bottom mirror))
    )
    (fp_rect (start -0.925 0.47) (end 0.925 -0.47)
      (stroke (width 0.05) (type default)) (fill none) (layer "B.CrtYd"))
    (fp_line (start -0.494 -0.248) (end -0.494 0.25)
      (stroke (width 0.15) (type solid)) (layer "B.Fab"))
    (fp_line (start -0.494 0.25) (end 0.504 0.25)
      (stroke (width 0.15) (type solid)) (layer "B.Fab"))
    (fp_line (start 0.504 -0.248) (end -0.494 -0.248)
      (stroke (width 0.15) (type solid)) (layer "B.Fab"))
    (fp_line (start 0.504 0.25) (end 0.504 -0.248)
      (stroke (width 0.15) (type solid)) (layer "B.Fab"))
    (pad "1" smd roundrect (at -0.48 0) (size 0.59 0.64) (layers "B.Cu" "B.Paste" "B.Mask") (roundrect_rratio 0.25)
      (net 1 "GND") (pintype "passive"))
    (pad "2" smd roundrect (at 0.48 0) (size 0.59 0.64) (layers "B.Cu" "B.Paste" "B.Mask") (roundrect_rratio 0.25)
      (net 106 "Net-(C53-Pad2)") (pintype "passive"))
  )
	(footprint "antmicro-footprints:R_0402_1005Metric" (layer "B.Cu")
    (at 111.725 81.66)
    (descr "Resistor SMD 0402")
    (tags "resistor SMD 0402")
    (property "Author" "Antmicro")
    (property "Current" "1A")
    (property "License" "Apache-2.0")
    (property "MPN" "ERJ2GE0R00X")
    (property "Manufacturer" "Panasonic")
    (property "Sheetfile" "power.kicad_sch")
    (property "Sheetname" "Power")
    (property "Tolerance" "")
    (property "Val" "0R")
    (property "ki_description" "SMD Chip Resistor, Jumper, 0 ohm, 100 mW, 0402 [1005 Metric], Thick Film, General Purpose")
    (property "ki_keywords" "0402, SMT, RESISTOR, PASSIVE")
    (attr smd)
    (fp_text reference "R26" (at 1.051 -4.698 180) (layer "B.SilkS")
        (effects (font (size 0.7 0.7) (thickness 0.15)) (justify left bottom mirror))
    )
    (fp_text value "R_0R_0402" (at -1.011843 -1.772047 180) (layer "B.Fab")
        (effects (font (size 0.7 0.7) (thickness 0.15)) (justify left bottom mirror))
    )
    (fp_text user "License: Apache-2.0" (at -0.95 -5.169 180) (layer "B.Fab") hide
        (effects (font (size 0.7 0.7) (thickness 0.15)) (justify left bottom mirror))
    )
    (fp_text user "${REFERENCE}" (at -0.95 -3.168 180) (layer "B.Fab") hide
        (effects (font (size 0.7 0.7) (thickness 0.15)) (justify left bottom mirror))
    )
    (fp_text user "Author: Antmicro" (at -0.95 -4.169 180) (layer "B.Fab") hide
        (effects (font (size 0.7 0.7) (thickness 0.15)) (justify left bottom mirror))
    )
    (fp_rect (start -0.925 0.47) (end 0.925 -0.47)
      (stroke (width 0.05) (type default)) (fill none) (layer "B.CrtYd"))
    (fp_rect (start -0.5 0.25) (end 0.5 -0.25)
      (stroke (width 0.15) (type solid)) (fill none) (layer "B.Fab"))
    (pad "1" smd roundrect (at -0.48 0) (size 0.59 0.64) (layers "B.Cu" "B.Paste" "B.Mask") (roundrect_rratio 0.25)
      (net 97 "Net-(U1-EXTVCC)") (pintype "passive"))
    (pad "2" smd roundrect (at 0.48 0) (size 0.59 0.64) (layers "B.Cu" "B.Paste" "B.Mask") (roundrect_rratio 0.25)
      (net 75 "Net-(C32-Pad2)") (pintype "passive"))
  )
	(footprint "antmicro-footprints:C_0402_1005Metric" (layer "B.Cu")
    (at 108.915 82.67 180)
    (descr "Capacitor SMD 0402")
    (tags "capacitor SMD 0402")
    (property "Author" "Antmicro")
    (property "Dielectric" "")
    (property "License" "Apache-2.0")
    (property "MPN" "C1005X6S1A105K050BC")
    (property "Manufacturer" "TDK")
    (property "Sheetfile" "power.kicad_sch")
    (property "Sheetname" "Power")
    (property "Val" "1u")
    (property "Voltage" "")
    (property "ki_description" "SMD Multilayer Ceramic Capacitor, 1 µF, 10 V, 0402 [1005 Metric], ± 10%, X6S, C")
    (property "ki_keywords" "0402, SMT, CAPACITOR, PASSIVE, CERAMIC, MLCC")
    (attr smd)
    (fp_text reference "C18" (at -1.067 5.708) (layer "B.SilkS")
        (effects (font (size 0.7 0.7) (thickness 0.15)) (justify left bottom mirror))
    )
    (fp_text value "C_1u_0402" (at -1.022927 -2.155213) (layer "B.Fab")
        (effects (font (size 0.7 0.7) (thickness 0.15)) (justify left bottom mirror))
    )
    (fp_text user "Author: Antmicro" (at -0.939 -3.399) (layer "B.Fab") hide
        (effects (font (size 0.7 0.7) (thickness 0.15)) (justify left bottom mirror))
    )
    (fp_text user "License: Apache-2.0" (at -0.939 -5.799) (layer "B.Fab") hide
        (effects (font (size 0.7 0.7) (thickness 0.15)) (justify left bottom mirror))
    )
    (fp_text user "${REFERENCE}" (at -0.939 -4.599) (layer "B.Fab") hide
        (effects (font (size 0.7 0.7) (thickness 0.15)) (justify left bottom mirror))
    )
    (fp_rect (start -0.925 0.47) (end 0.925 -0.47)
      (stroke (width 0.05) (type default)) (fill none) (layer "B.CrtYd"))
    (fp_line (start -0.494 -0.248) (end -0.494 0.25)
      (stroke (width 0.15) (type solid)) (layer "B.Fab"))
    (fp_line (start -0.494 0.25) (end 0.504 0.25)
      (stroke (width 0.15) (type solid)) (layer "B.Fab"))
    (fp_line (start 0.504 -0.248) (end -0.494 -0.248)
      (stroke (width 0.15) (type solid)) (layer "B.Fab"))
    (fp_line (start 0.504 0.25) (end 0.504 -0.248)
      (stroke (width 0.15) (type solid)) (layer "B.Fab"))
    (pad "1" smd roundrect (at -0.48 0 180) (size 0.59 0.64) (layers "B.Cu" "B.Paste" "B.Mask") (roundrect_rratio 0.25)
      (net 1 "GND") (pintype "passive"))
    (pad "2" smd roundrect (at 0.48 0 180) (size 0.59 0.64) (layers "B.Cu" "B.Paste" "B.Mask") (roundrect_rratio 0.25)
      (net 91 "Net-(U1-INTVCC)") (pintype "passive"))
  )
	(footprint "antmicro-footprints:C_0402_1005Metric" (layer "B.Cu")
    (at 139.5 92.65 -90)
    (descr "Capacitor SMD 0402")
    (tags "capacitor SMD 0402")
    (property "Author" "Antmicro")
    (property "Dielectric" "")
    (property "License" "Apache-2.0")
    (property "MPN" "CC0402KRX5R6BB224")
    (property "Manufacturer" "YAGEO")
    (property "Sheetfile" "tb.kicad_sch")
    (property "Sheetname" "TB Controller")
    (property "Val" "220n")
    (property "Voltage" "")
    (property "ki_description" "SMD Multilayer Ceramic Capacitor, 0.22 µF, 10 V, 0402 [1005 Metric], ± 10%, X5R, CC Series")
    (property "ki_keywords" "0402, SMT, CAPACITOR, PASSIVE, MLCC, CERAMIC")
    (attr smd)
    (fp_text reference "C112" (at -3.877 -0.47 90) (layer "B.SilkS")
        (effects (font (size 0.7 0.7) (thickness 0.15)) (justify left bottom mirror))
    )
    (fp_text value "C_220n_0402" (at -1.022927 -2.155213 90) (layer "B.Fab")
        (effects (font (size 0.7 0.7) (thickness 0.15)) (justify left bottom mirror))
    )
    (fp_text user "Author: Antmicro" (at -0.939 -3.399 90) (layer "B.Fab") hide
        (effects (font (size 0.7 0.7) (thickness 0.15)) (justify left bottom mirror))
    )
    (fp_text user "License: Apache-2.0" (at -0.939 -5.799 90) (layer "B.Fab") hide
        (effects (font (size 0.7 0.7) (thickness 0.15)) (justify left bottom mirror))
    )
    (fp_text user "${REFERENCE}" (at -0.939 -4.599 90) (layer "B.Fab") hide
        (effects (font (size 0.7 0.7) (thickness 0.15)) (justify left bottom mirror))
    )
    (fp_rect (start -0.925 0.47) (end 0.925 -0.47)
      (stroke (width 0.05) (type default)) (fill none) (layer "B.CrtYd"))
    (fp_line (start -0.494 -0.248) (end -0.494 0.25)
      (stroke (width 0.15) (type solid)) (layer "B.Fab"))
    (fp_line (start -0.494 0.25) (end 0.504 0.25)
      (stroke (width 0.15) (type solid)) (layer "B.Fab"))
    (fp_line (start 0.504 -0.248) (end -0.494 -0.248)
      (stroke (width 0.15) (type solid)) (layer "B.Fab"))
    (fp_line (start 0.504 0.25) (end 0.504 -0.248)
      (stroke (width 0.15) (type solid)) (layer "B.Fab"))
    (pad "1" smd roundrect (at -0.48 0 270) (size 0.59 0.64) (layers "B.Cu" "B.Paste" "B.Mask") (roundrect_rratio 0.25)
      (net 83 "/TB Controller/TX3_P") (pintype "passive"))
    (pad "2" smd roundrect (at 0.48 0 270) (size 0.59 0.64) (layers "B.Cu" "B.Paste" "B.Mask") (roundrect_rratio 0.25)
      (net 31 "PCIE_TX3_P") (pintype "passive"))
  )
	(footprint "antmicro-footprints:R_0402_1005Metric" (layer "B.Cu")
    (at 151.41 64.97 180)
    (descr "Resistor SMD 0402")
    (tags "resistor SMD 0402")
    (property "Author" "Antmicro")
    (property "License" "Apache-2.0")
    (property "MPN" "CR0402-FX-1003GLF")
    (property "Manufacturer" "Bourns")
    (property "Sheetfile" "power.kicad_sch")
    (property "Sheetname" "Power")
    (property "Tolerance" "1%")
    (property "Val" "100k")
    (property "ki_description" "SMD Chip Resistor, 100 kohm, ± 1%, 62.5 mW, 0402 [1005 Metric], Thick Film, General Purpose")
    (property "ki_keywords" "0402, SMT, RESISTOR, PASSIVE")
    (attr smd)
    (fp_text reference "R10" (at 0.961516 -0.398303) (layer "B.SilkS")
        (effects (font (size 0.7 0.7) (thickness 0.15)) (justify left bottom mirror))
    )
    (fp_text value "R_100k_0402" (at -1.011843 -1.772047) (layer "B.Fab")
        (effects (font (size 0.7 0.7) (thickness 0.15)) (justify left bottom mirror))
    )
    (fp_text user "${REFERENCE}" (at -0.95 -3.168) (layer "B.Fab") hide
        (effects (font (size 0.7 0.7) (thickness 0.15)) (justify left bottom mirror))
    )
    (fp_text user "License: Apache-2.0" (at -0.95 -5.169) (layer "B.Fab") hide
        (effects (font (size 0.7 0.7) (thickness 0.15)) (justify left bottom mirror))
    )
    (fp_text user "Author: Antmicro" (at -0.95 -4.169) (layer "B.Fab") hide
        (effects (font (size 0.7 0.7) (thickness 0.15)) (justify left bottom mirror))
    )
    (fp_rect (start -0.925 0.47) (end 0.925 -0.47)
      (stroke (width 0.05) (type default)) (fill none) (layer "B.CrtYd"))
    (fp_rect (start -0.5 0.25) (end 0.5 -0.25)
      (stroke (width 0.15) (type solid)) (fill none) (layer "B.Fab"))
    (pad "1" smd roundrect (at -0.48 0 180) (size 0.59 0.64) (layers "B.Cu" "B.Paste" "B.Mask") (roundrect_rratio 0.25)
      (net 9 "/Power/TPS_3V3") (pintype "passive"))
    (pad "2" smd roundrect (at 0.48 0 180) (size 0.59 0.64) (layers "B.Cu" "B.Paste" "B.Mask") (roundrect_rratio 0.25)
      (net 23 "AUX_N") (pintype "passive"))
  )
	(footprint "antmicro-footprints:R_0402_1005Metric" (layer "B.Cu")
    (at 117.15 91.63 90)
    (descr "Resistor SMD 0402")
    (tags "resistor SMD 0402")
    (property "Author" "Antmicro")
    (property "License" "Apache-2.0")
    (property "MPN" "CR0402-FX-1002GLF")
    (property "Manufacturer" "Bourns")
    (property "Sheetfile" "power.kicad_sch")
    (property "Sheetname" "Power")
    (property "Tolerance" "1%")
    (property "Val" "10k")
    (property "ki_description" "SMD Chip Resistor, 10 kohm, ± 1%, 62.5 mW, 0402 [1005 Metric], Thick Film, General Purpose")
    (property "ki_keywords" "0402, SMT, RESISTOR, PASSIVE")
    (attr smd)
    (fp_text reference "R94" (at 1.079 3.515 270) (layer "B.SilkS")
        (effects (font (size 0.7 0.7) (thickness 0.15)) (justify left bottom mirror))
    )
    (fp_text value "R_10k_0402" (at -1.011843 -1.772047 270) (layer "B.Fab")
        (effects (font (size 0.7 0.7) (thickness 0.15)) (justify left bottom mirror))
    )
    (fp_text user "${REFERENCE}" (at -0.95 -3.168 270) (layer "B.Fab") hide
        (effects (font (size 0.7 0.7) (thickness 0.15)) (justify left bottom mirror))
    )
    (fp_text user "License: Apache-2.0" (at -0.95 -5.169 270) (layer "B.Fab") hide
        (effects (font (size 0.7 0.7) (thickness 0.15)) (justify left bottom mirror))
    )
    (fp_text user "Author: Antmicro" (at -0.95 -4.169 270) (layer "B.Fab") hide
        (effects (font (size 0.7 0.7) (thickness 0.15)) (justify left bottom mirror))
    )
    (fp_rect (start -0.925 0.47) (end 0.925 -0.47)
      (stroke (width 0.05) (type default)) (fill none) (layer "B.CrtYd"))
    (fp_rect (start -0.5 0.25) (end 0.5 -0.25)
      (stroke (width 0.15) (type solid)) (fill none) (layer "B.Fab"))
    (pad "1" smd roundrect (at -0.48 0 90) (size 0.59 0.64) (layers "B.Cu" "B.Paste" "B.Mask") (roundrect_rratio 0.25)
      (net 1 "GND") (pintype "passive"))
    (pad "2" smd roundrect (at 0.48 0 90) (size 0.59 0.64) (layers "B.Cu" "B.Paste" "B.Mask") (roundrect_rratio 0.25)
      (net 144 "Net-(Q4-REF)") (pintype "passive"))
  )
	(footprint "antmicro-footprints:R_0402_1005Metric" (layer "B.Cu")
    (at 108.915 81.66)
    (descr "Resistor SMD 0402")
    (tags "resistor SMD 0402")
    (property "Author" "Antmicro")
    (property "License" "Apache-2.0")
    (property "MPN" "CR0402-FX-1003GLF")
    (property "Manufacturer" "Bourns")
    (property "Sheetfile" "power.kicad_sch")
    (property "Sheetname" "Power")
    (property "Tolerance" "1%")
    (property "Val" "100k")
    (property "ki_description" "SMD Chip Resistor, 100 kohm, ± 1%, 62.5 mW, 0402 [1005 Metric], Thick Film, General Purpose")
    (property "ki_keywords" "0402, SMT, RESISTOR, PASSIVE")
    (attr smd)
    (fp_text reference "R22" (at 1.067 -5.714 180) (layer "B.SilkS")
        (effects (font (size 0.7 0.7) (thickness 0.15)) (justify left bottom mirror))
    )
    (fp_text value "R_100k_0402" (at -1.011843 -1.772047 180) (layer "B.Fab")
        (effects (font (size 0.7 0.7) (thickness 0.15)) (justify left bottom mirror))
    )
    (fp_text user "Author: Antmicro" (at -0.95 -4.169 180) (layer "B.Fab") hide
        (effects (font (size 0.7 0.7) (thickness 0.15)) (justify left bottom mirror))
    )
    (fp_text user "License: Apache-2.0" (at -0.95 -5.169 180) (layer "B.Fab") hide
        (effects (font (size 0.7 0.7) (thickness 0.15)) (justify left bottom mirror))
    )
    (fp_text user "${REFERENCE}" (at -0.95 -3.168 180) (layer "B.Fab") hide
        (effects (font (size 0.7 0.7) (thickness 0.15)) (justify left bottom mirror))
    )
    (fp_rect (start -0.925 0.47) (end 0.925 -0.47)
      (stroke (width 0.05) (type default)) (fill none) (layer "B.CrtYd"))
    (fp_rect (start -0.5 0.25) (end 0.5 -0.25)
      (stroke (width 0.15) (type solid)) (fill none) (layer "B.Fab"))
    (pad "1" smd roundrect (at -0.48 0) (size 0.59 0.64) (layers "B.Cu" "B.Paste" "B.Mask") (roundrect_rratio 0.25)
      (net 91 "Net-(U1-INTVCC)") (pintype "passive"))
    (pad "2" smd roundrect (at 0.48 0) (size 0.59 0.64) (layers "B.Cu" "B.Paste" "B.Mask") (roundrect_rratio 0.25)
      (net 157 "Net-(U1-~{PGOOD})") (pintype "passive"))
  )
	(footprint "antmicro-footprints:C_0402_1005Metric" (layer "B.Cu")
    (at 122.998 76.97 180)
    (descr "Capacitor SMD 0402")
    (tags "capacitor SMD 0402")
    (property "Author" "Antmicro")
    (property "Dielectric" "C0G")
    (property "License" "Apache-2.0")
    (property "MPN" "GCM1555C1H100GA16D")
    (property "Manufacturer" "Murata")
    (property "Sheetfile" "tb.kicad_sch")
    (property "Sheetname" "TB Controller")
    (property "Val" "10p")
    (property "Voltage" "50V")
    (property "ki_description" "SMD Multilayer Ceramic Capacitor, 10 pF, 50 V, 0402 [1005 Metric], ± 2%, C0G / NP0, GCM")
    (property "ki_keywords" "0402, SMT, CAPACITOR, PASSIVE")
    (attr smd)
    (fp_text reference "C114" (at -1.081 -1.516) (layer "B.SilkS")
        (effects (font (size 0.7 0.7) (thickness 0.15)) (justify left bottom mirror))
    )
    (fp_text value "C_10p_0402" (at -1.022927 -2.155213) (layer "B.Fab")
        (effects (font (size 0.7 0.7) (thickness 0.15)) (justify left bottom mirror))
    )
    (fp_text user "${REFERENCE}" (at -0.939 -4.599) (layer "B.Fab") hide
        (effects (font (size 0.7 0.7) (thickness 0.15)) (justify left bottom mirror))
    )
    (fp_text user "Author: Antmicro" (at -0.939 -3.399) (layer "B.Fab") hide
        (effects (font (size 0.7 0.7) (thickness 0.15)) (justify left bottom mirror))
    )
    (fp_text user "License: Apache-2.0" (at -0.939 -5.799) (layer "B.Fab") hide
        (effects (font (size 0.7 0.7) (thickness 0.15)) (justify left bottom mirror))
    )
    (fp_rect (start -0.925 0.47) (end 0.925 -0.47)
      (stroke (width 0.05) (type default)) (fill none) (layer "B.CrtYd"))
    (fp_line (start -0.494 -0.248) (end -0.494 0.25)
      (stroke (width 0.15) (type solid)) (layer "B.Fab"))
    (fp_line (start -0.494 0.25) (end 0.504 0.25)
      (stroke (width 0.15) (type solid)) (layer "B.Fab"))
    (fp_line (start 0.504 -0.248) (end -0.494 -0.248)
      (stroke (width 0.15) (type solid)) (layer "B.Fab"))
    (fp_line (start 0.504 0.25) (end 0.504 -0.248)
      (stroke (width 0.15) (type solid)) (layer "B.Fab"))
    (pad "1" smd roundrect (at -0.48 0 180) (size 0.59 0.64) (layers "B.Cu" "B.Paste" "B.Mask") (roundrect_rratio 0.25)
      (net 1 "GND") (pintype "passive"))
    (pad "2" smd roundrect (at 0.48 0 180) (size 0.59 0.64) (layers "B.Cu" "B.Paste" "B.Mask") (roundrect_rratio 0.25)
      (net 116 "Net-(U6-XIN{slash}CLKIN)") (pintype "passive"))
  )
)
